(kicad_pcb
	(version 20211014)
	(generator pcbnew)
	(general
    (thickness 1.6)
  )
	(paper "A4")
	(title_block
    (title "SA800U (Snapdragon 845) Baseboard")
    (date "2023-10-19")
    (rev "1.0.3")
    (company "Antmicro Ltd.")
    (comment 1 "www.antmicro.com")
		(comment 9 "footprints 456-461 of 589")
	)
	(layers
    (0 "F.Cu" signal)
    (1 "In1.Cu" power)
    (2 "In2.Cu" signal)
    (3 "In3.Cu" signal)
    (4 "In4.Cu" power)
    (31 "B.Cu" signal)
    (32 "B.Adhes" user "B.Adhesive")
    (33 "F.Adhes" user "F.Adhesive")
    (34 "B.Paste" user)
    (35 "F.Paste" user)
    (36 "B.SilkS" user "B.Silkscreen")
    (37 "F.SilkS" user "F.Silkscreen")
    (38 "B.Mask" user)
    (39 "F.Mask" user)
    (40 "Dwgs.User" user "User.Drawings")
    (41 "Cmts.User" user "User.Comments")
    (42 "Eco1.User" user "User.Eco1")
    (43 "Eco2.User" user "User.Eco2")
    (44 "Edge.Cuts" user)
    (45 "Margin" user)
    (46 "B.CrtYd" user "B.Courtyard")
    (47 "F.CrtYd" user "F.Courtyard")
    (48 "B.Fab" user)
    (49 "F.Fab" user)
  )
	(footprint "sa800u-baseboard-hw-footprints:R_0402_1005Metric" (layer "B.Cu")
    (tedit 5FD9C158)
    (at 81.25 150 -90)
    (descr "Resistor SMD 0402")
    (tags "resistor SMD 0402")
    (property "Author" "Antmicro")
    (property "License" "Apache-2.0")
    (property "MPN" "CR0402-FX-1002GLF")
    (property "Manufacturer" "Bourns")
    (property "Sheetfile" "psu.kicad_sch")
    (property "Sheetname" "PSU")
    (property "Tolerance" "1%")
    (property "Val" "10k")
    (attr smd)
    (fp_text reference "R111" (at -1.05 0.64 90) (layer "B.SilkS")
      (effects (font (size 0.7 0.7) (thickness 0.15)) (justify left bottom mirror))
    )
    (fp_text value "R_10k_0402" (at 0 -1.4 90) (layer "B.Fab")
      (effects (font (size 0.7 0.7) (thickness 0.15)) (justify left bottom mirror))
    )
    (fp_text user "${REFERENCE}" (at -0.95 -3.168 90) (layer "B.Fab") hide
      (effects (font (size 0.7 0.7) (thickness 0.15)) (justify left bottom mirror))
    )
    (fp_text user "License: Apache-2.0" (at -0.95 -5.169 90) (layer "B.Fab") hide
      (effects (font (size 0.7 0.7) (thickness 0.15)) (justify left bottom mirror))
    )
    (fp_text user "Author: Antmicro" (at -0.95 -4.169 90) (layer "B.Fab") hide
      (effects (font (size 0.7 0.7) (thickness 0.15)) (justify left bottom mirror))
    )
    (fp_rect (start -0.93 0.47) (end 0.93 -0.47) (layer "B.CrtYd") (width 0.05) (fill none))
    (fp_rect (start -0.5 0.25) (end 0.5 -0.25) (layer "B.Fab") (width 0.15) (fill none))
    (pad "1" smd roundrect (at -0.485 0 270) (size 0.59 0.64) (layers "B.Cu" "B.Paste" "B.Mask") (roundrect_rratio 0.25)
      (net 388 "Net-(Q8-Pad3)") (pintype "passive"))
    (pad "2" smd roundrect (at 0.485 0 270) (size 0.59 0.64) (layers "B.Cu" "B.Paste" "B.Mask") (roundrect_rratio 0.25)
      (net 375 "Net-(D24-Pad2)") (pintype "passive"))
  )
	(footprint "sa800u-baseboard-hw-footprints:R_0402_1005Metric" (layer "B.Cu")
    (tedit 5FD9C158)
    (at 93.4 150.25 -90)
    (descr "Resistor SMD 0402")
    (tags "resistor SMD 0402")
    (property "Author" "Antmicro")
    (property "License" "Apache-2.0")
    (property "MPN" "CR0402-FX-1002GLF")
    (property "Manufacturer" "Bourns")
    (property "Sheetfile" "psu.kicad_sch")
    (property "Sheetname" "PSU")
    (property "Tolerance" "1%")
    (property "Val" "10k")
    (attr smd)
    (fp_text reference "R115" (at -1.25 -1.32 90) (layer "B.SilkS")
      (effects (font (size 0.7 0.7) (thickness 0.15)) (justify left bottom mirror))
    )
    (fp_text value "R_10k_0402" (at 0 -1.4 90) (layer "B.Fab")
      (effects (font (size 0.7 0.7) (thickness 0.15)) (justify left bottom mirror))
    )
    (fp_text user "${REFERENCE}" (at -0.95 -3.168 90) (layer "B.Fab") hide
      (effects (font (size 0.7 0.7) (thickness 0.15)) (justify left bottom mirror))
    )
    (fp_text user "Author: Antmicro" (at -0.95 -4.169 90) (layer "B.Fab") hide
      (effects (font (size 0.7 0.7) (thickness 0.15)) (justify left bottom mirror))
    )
    (fp_text user "License: Apache-2.0" (at -0.95 -5.169 90) (layer "B.Fab") hide
      (effects (font (size 0.7 0.7) (thickness 0.15)) (justify left bottom mirror))
    )
    (fp_rect (start -0.93 0.47) (end 0.93 -0.47) (layer "B.CrtYd") (width 0.05) (fill none))
    (fp_rect (start -0.5 0.25) (end 0.5 -0.25) (layer "B.Fab") (width 0.15) (fill none))
    (pad "1" smd roundrect (at -0.485 0 270) (size 0.59 0.64) (layers "B.Cu" "B.Paste" "B.Mask") (roundrect_rratio 0.25)
      (net 389 "Net-(Q10-Pad3)") (pintype "passive"))
    (pad "2" smd roundrect (at 0.485 0 270) (size 0.59 0.64) (layers "B.Cu" "B.Paste" "B.Mask") (roundrect_rratio 0.25)
      (net 376 "Net-(D25-Pad2)") (pintype "passive"))
  )
	(footprint "sa800u-baseboard-hw-footprints:SOT-23-3" (layer "B.Cu")
    (tedit 5D5D4314)
    (at 84.2 123 90)
    (property "Author" "Antmicro")
    (property "License" "Apache-2.0")
    (property "MPN" "BSS84")
    (property "Manufacturer" "ON Semiconductor")
    (property "Sheetfile" "psu.kicad_sch")
    (property "Sheetname" "PSU")
    (attr smd)
    (fp_text reference "Q14" (at 0.98 2.65) (layer "B.SilkS")
      (effects (font (size 0.7 0.7) (thickness 0.15)) (justify left bottom mirror))
    )
    (fp_text value "BSS84" (at -1.9 -2.7 270) (layer "B.Fab")
      (effects (font (size 0.7 0.7) (thickness 0.15)) (justify left bottom mirror))
    )
    (fp_text user "License: Apache-2.0" (at -1.8 -6.8 270) (layer "B.Fab") hide
      (effects (font (size 0.7 0.7) (thickness 0.15)) (justify left bottom mirror))
    )
    (fp_text user "${REFERENCE}" (at -1.837 -4 270) (layer "B.Fab") hide
      (effects (font (size 0.7 0.7) (thickness 0.15)) (justify left bottom mirror))
    )
    (fp_text user "Author: Antmicro" (at -1.837 -5.3 270) (layer "B.Fab") hide
      (effects (font (size 0.7 0.7) (thickness 0.15)) (justify left bottom mirror))
    )
    (fp_line (start -0.85 1.35) (end -0.7 1.5) (layer "B.SilkS") (width 0.15))
    (fp_line (start 0.7 -0.4) (end 0.7 -1.5) (layer "B.SilkS") (width 0.15))
    (fp_line (start 0.7 -1.5) (end -0.7 -1.5) (layer "B.SilkS") (width 0.15))
    (fp_line (start 0.7 0.4) (end 0.7 1.5) (layer "B.SilkS") (width 0.15))
    (fp_line (start -0.7 -1.5) (end -0.7 -1.35) (layer "B.SilkS") (width 0.15))
    (fp_line (start 0.7 1.5) (end -0.7 1.5) (layer "B.SilkS") (width 0.15))
    (fp_line (start -1.45 1.35) (end -0.85 1.35) (layer "B.SilkS") (width 0.15))
    (fp_line (start -0.85 -1.4) (end -1.75 -1.4) (layer "B.CrtYd") (width 0.05))
    (fp_line (start -0.85 0.5) (end -1.75 0.5) (layer "B.CrtYd") (width 0.05))
    (fp_line (start -0.85 -1.65) (end -0.85 -1.4) (layer "B.CrtYd") (width 0.05))
    (fp_line (start -0.9 1.6) (end -0.9 1.4) (layer "B.CrtYd") (width 0.05))
    (fp_line (start -0.9 1.4) (end -1.75 1.4) (layer "B.CrtYd") (width 0.05))
    (fp_line (start -0.85 -0.5) (end -0.85 0.5) (layer "B.CrtYd") (width 0.05))
    (fp_line (start 0.85 -1.65) (end -0.85 -1.65) (layer "B.CrtYd") (width 0.05))
    (fp_line (start -1.75 -0.5) (end -0.85 -0.5) (layer "B.CrtYd") (width 0.05))
    (fp_line (start 0.825 1.6) (end 0.825 0.45) (layer "B.CrtYd") (width 0.05))
    (fp_line (start 1.75 -0.45) (end 0.85 -0.45) (layer "B.CrtYd") (width 0.05))
    (fp_line (start 1.75 0.45) (end 1.75 -0.45) (layer "B.CrtYd") (width 0.05))
    (fp_line (start -0.9 1.6) (end 0.825 1.6) (layer "B.CrtYd") (width 0.05))
    (fp_line (start 0.85 -0.45) (end 0.85 -1.65) (layer "B.CrtYd") (width 0.05))
    (fp_line (start -1.75 0.5) (end -1.75 1.4) (layer "B.CrtYd") (width 0.05))
    (fp_line (start -1.75 -1.4) (end -1.75 -0.5) (layer "B.CrtYd") (width 0.05))
    (fp_line (start 0.825 0.45) (end 1.75 0.45) (layer "B.CrtYd") (width 0.05))
    (fp_line (start 0.688 -1.519) (end 0.688 1.52) (layer "B.Fab") (width 0.15))
    (fp_line (start -0.437 1.526) (end 0.688 1.526) (layer "B.Fab") (width 0.15))
    (fp_line (start -0.712 -1.519) (end 0.688 -1.519) (layer "B.Fab") (width 0.15))
    (fp_line (start -0.712 1.325) (end -0.712 -1.523) (layer "B.Fab") (width 0.15))
    (fp_line (start -0.437 1.526) (end -0.712 1.325) (layer "B.Fab") (width 0.15))
    (pad "1" smd roundrect (at -1.1 0.951 90) (size 1 0.6) (layers "B.Cu" "B.Paste" "B.Mask") (roundrect_rratio 0.15)
      (net 156 "/PSU/BYPASS_EN") (pinfunction "G") (pintype "bidirectional"))
    (pad "2" smd roundrect (at -1.1 -0.949 90) (size 1 0.6) (layers "B.Cu" "B.Paste" "B.Mask") (roundrect_rratio 0.15)
      (net 1 "GND") (pinfunction "D") (pintype "bidirectional"))
    (pad "3" smd roundrect (at 1.1 0.0005 90) (size 1 0.6) (layers "B.Cu" "B.Paste" "B.Mask") (roundrect_rratio 0.15)
      (net 348 "Net-(Q14-Pad3)") (pinfunction "S") (pintype "bidirectional"))
  )
	(footprint "sa800u-baseboard-hw-footprints:Nexperia_DFN-10_2.5x1mm_P0.5mm" (layer "B.Cu")
    (tedit 6215DC23)
    (at 95.5 142.9 -90)
    (property "Author" "Antmicro")
    (property "License" "Apache-2.0")
    (property "MPN" "PUSB3F96X")
    (property "Manufacturer" "Nexperia")
    (property "Sheetfile" "usb-c-interface.kicad_sch")
    (property "Sheetname" "USB-C Interface ")
    (attr smd)
    (fp_text reference "D7" (at -1.5 -0.72 180) (layer "B.SilkS")
      (effects (font (size 0.7 0.7) (thickness 0.15)) (justify left bottom mirror))
    )
    (fp_text value "PUSB3F96X_PASS" (at -0.016 -1.705 90) (layer "B.Fab")
      (effects (font (size 0.7 0.7) (thickness 0.15)) (justify left bottom mirror))
    )
    (fp_text user "License: Apache-2.0" (at -1.367 -6.105 90) (layer "B.Fab") hide
      (effects (font (size 0.7 0.7) (thickness 0.15)) (justify left bottom mirror))
    )
    (fp_text user "Author: Antmicro" (at -1.367 -4.905 90) (layer "B.Fab") hide
      (effects (font (size 0.7 0.7) (thickness 0.15)) (justify left bottom mirror))
    )
    (fp_text user "${REFERENCE}" (at -1.367 -3.704 90) (layer "B.Fab") hide
      (effects (font (size 0.7 0.7) (thickness 0.15)) (justify left bottom mirror))
    )
    (fp_line (start -1.266 0.396) (end -1.266 -0.405) (layer "B.SilkS") (width 0.15))
    (fp_line (start 1.233 -0.405) (end 1.233 0.396) (layer "B.SilkS") (width 0.15))
    (fp_circle (center -1.317 -0.704) (end -1.266 -0.704) (layer "B.SilkS") (width 0.15) (fill solid))
    (fp_rect (start -1.4 0.7) (end 1.4 -0.7) (layer "B.CrtYd") (width 0.05) (fill none))
    (pad "1" smd rect (at -1.016 -0.392 270) (size 0.2 0.475) (layers "B.Cu" "B.Paste" "B.Mask")
      (net 368 "unconnected-(D7-Pad1)") (pinfunction "CH1") (pintype "passive+no_connect"))
    (pad "2" smd rect (at -0.517 -0.392 270) (size 0.2 0.475) (layers "B.Cu" "B.Paste" "B.Mask")
      (net 331 "/USB-C Interface /USB1_SBU_P") (pinfunction "CH2") (pintype "passive"))
    (pad "3" smd rect (at -0.016 -0.392 270) (size 0.2 0.475) (layers "B.Cu" "B.Paste" "B.Mask")
      (net 1 "GND") (pinfunction "GND") (pintype "passive"))
    (pad "4" smd rect (at 0.482 -0.392 270) (size 0.2 0.475) (layers "B.Cu" "B.Paste" "B.Mask")
      (net 330 "/USB-C Interface /USB1_SBU_N") (pinfunction "CH3") (pintype "passive"))
    (pad "5" smd rect (at 0.982 -0.392 270) (size 0.2 0.475) (layers "B.Cu" "B.Paste" "B.Mask")
      (net 369 "unconnected-(D7-Pad5)") (pinfunction "CH4") (pintype "passive+no_connect"))
    (pad "6" smd rect (at 0.982 0.383 90) (size 0.2 0.475) (layers "B.Cu" "B.Paste" "B.Mask")
      (net 369 "unconnected-(D7-Pad5)") (pinfunction "CH4") (pintype "passive+no_connect"))
    (pad "7" smd rect (at 0.482 0.383 90) (size 0.2 0.475) (layers "B.Cu" "B.Paste" "B.Mask")
      (net 330 "/USB-C Interface /USB1_SBU_N") (pinfunction "CH3") (pintype "passive"))
    (pad "8" smd rect (at -0.016 0.383 90) (size 0.2 0.475) (layers "B.Cu" "B.Paste" "B.Mask")
      (net 1 "GND") (pinfunction "GND") (pintype "passive"))
    (pad "9" smd rect (at -0.517 0.383 90) (size 0.2 0.475) (layers "B.Cu" "B.Paste" "B.Mask")
      (net 331 "/USB-C Interface /USB1_SBU_P") (pinfunction "CH2") (pintype "passive"))
    (pad "10" smd rect (at -1.016 0.383 90) (size 0.2 0.475) (layers "B.Cu" "B.Paste" "B.Mask")
      (net 368 "unconnected-(D7-Pad1)") (pinfunction "CH1") (pintype "passive+no_connect"))
  )
	(footprint "sa800u-baseboard-hw-footprints:L_Murata_025020_0605Metric" (layer "B.Cu")
    (tedit 61AA2C4F)
    (at 95 93.7 90)
    (property "Author" "Antmicro")
    (property "License" "Apache-2.0")
    (property "MPN" "NFP0QHB242HS2D")
    (property "Manufacturer" "Murata")
    (property "Sheetfile" "camera-interface.kicad_sch")
    (property "Sheetname" "Camera Interface")
    (attr smd)
    (fp_text reference "L18" (at -0.44 0.33 270) (layer "B.SilkS")
      (effects (font (size 0.7 0.7) (thickness 0.15)) (justify left bottom mirror))
    )
    (fp_text value "NFP0QHB242HS2D" (at 0 -1.55 270) (layer "B.Fab")
      (effects (font (size 0.7 0.7) (thickness 0.15)) (justify left bottom mirror))
    )
    (fp_text user "Author: Antmicro" (at -1.027 -4.605 270) (layer "B.Fab") hide
      (effects (font (size 0.7 0.7) (thickness 0.15)) (justify left bottom mirror))
    )
    (fp_text user "${REFERENCE}" (at -1.027 -3.406 270) (layer "B.Fab") hide
      (effects (font (size 0.7 0.7) (thickness 0.15)) (justify left bottom mirror))
    )
    (fp_text user "License: Apache-2.0" (at -1.027 -5.805 270) (layer "B.Fab") hide
      (effects (font (size 0.7 0.7) (thickness 0.15)) (justify left bottom mirror))
    )
    (fp_line (start 0.276 0.45) (end -0.276 0.45) (layer "B.SilkS") (width 0.15))
    (fp_line (start -0.276 -0.45) (end 0.276 -0.45) (layer "B.SilkS") (width 0.15))
    (fp_circle (center -0.5 0.5) (end -0.449 0.5) (layer "B.SilkS") (width 0.15) (fill solid))
    (fp_rect (start -0.5 0.6) (end 0.5 -0.6) (layer "B.CrtYd") (width 0.05) (fill none))
    (fp_line (start 0.275 0.351) (end -0.277 0.351) (layer "B.Fab") (width 0.15))
    (fp_line (start -0.277 0.351) (end -0.277 -0.349) (layer "B.Fab") (width 0.15))
    (fp_line (start -0.277 -0.349) (end 0.275 -0.349) (layer "B.Fab") (width 0.15))
    (fp_line (start 0.275 -0.349) (end 0.275 0.351) (layer "B.Fab") (width 0.15))
    (pad "1" smd rect (at -0.25 0.24 90) (size 0.3 0.23) (layers "B.Cu" "B.Paste" "B.Mask")
      (net 21 "CSI1_LN1_P") (pinfunction "1") (pintype "passive"))
    (pad "2" smd rect (at 0.248 0.24 90) (size 0.3 0.23) (layers "B.Cu" "B.Paste" "B.Mask")
      (net 272 "/Camera Interface/CSI1_LN1_FFC_P") (pinfunction "2") (pintype "passive"))
    (pad "3" smd rect (at 0.248 -0.239 90) (size 0.3 0.23) (layers "B.Cu" "B.Paste" "B.Mask")
      (net 273 "/Camera Interface/CSI1_LN1_FFC_N") (pinfunction "3") (pintype "passive"))
    (pad "4" smd rect (at -0.25 -0.239 90) (size 0.3 0.23) (layers "B.Cu" "B.Paste" "B.Mask")
      (net 22 "CSI1_LN1_N") (pinfunction "4") (pintype "passive"))
  )
	(footprint "sa800u-baseboard-hw-footprints:SOT-23-3" (layer "B.Cu")
    (tedit 5D5D4314)
    (at 72.2 118.6 90)
    (property "Author" "Antmicro")
    (property "License" "Apache-2.0")
    (property "MPN" "BSS84PH6327XTSA2")
    (property "Manufacturer" "Infineon Technologies")
    (property "Sheetfile" "psu.kicad_sch")
    (property "Sheetname" "PSU")
    (attr smd)
    (fp_text reference "Q15" (at 0.86 2.42) (layer "B.SilkS")
      (effects (font (size 0.7 0.7) (thickness 0.15)) (justify left bottom mirror))
    )
    (fp_text value "BSS84PH6327XTSA2" (at -1.9 -2.7 270) (layer "B.Fab")
      (effects (font (size 0.7 0.7) (thickness 0.15)) (justify left bottom mirror))
    )
    (fp_text user "${REFERENCE}" (at -1.837 -4 270) (layer "B.Fab") hide
      (effects (font (size 0.7 0.7) (thickness 0.15)) (justify left bottom mirror))
    )
    (fp_text user "License: Apache-2.0" (at -1.8 -6.8 270) (layer "B.Fab") hide
      (effects (font (size 0.7 0.7) (thickness 0.15)) (justify left bottom mirror))
    )
    (fp_text user "Author: Antmicro" (at -1.837 -5.3 270) (layer "B.Fab") hide
      (effects (font (size 0.7 0.7) (thickness 0.15)) (justify left bottom mirror))
    )
    (fp_line (start 0.7 1.5) (end -0.7 1.5) (layer "B.SilkS") (width 0.15))
    (fp_line (start -0.7 -1.5) (end -0.7 -1.35) (layer "B.SilkS") (width 0.15))
    (fp_line (start 0.7 -0.4) (end 0.7 -1.5) (layer "B.SilkS") (width 0.15))
    (fp_line (start -0.85 1.35) (end -0.7 1.5) (layer "B.SilkS") (width 0.15))
    (fp_line (start 0.7 -1.5) (end -0.7 -1.5) (layer "B.SilkS") (width 0.15))
    (fp_line (start -1.45 1.35) (end -0.85 1.35) (layer "B.SilkS") (width 0.15))
    (fp_line (start 0.7 0.4) (end 0.7 1.5) (layer "B.SilkS") (width 0.15))
    (fp_line (start -0.9 1.6) (end -0.9 1.4) (layer "B.CrtYd") (width 0.05))
    (fp_line (start 0.825 0.45) (end 1.75 0.45) (layer "B.CrtYd") (width 0.05))
    (fp_line (start -0.85 -0.5) (end -0.85 0.5) (layer "B.CrtYd") (width 0.05))
    (fp_line (start -1.75 0.5) (end -1.75 1.4) (layer "B.CrtYd") (width 0.05))
    (fp_line (start -0.85 0.5) (end -1.75 0.5) (layer "B.CrtYd") (width 0.05))
    (fp_line (start -0.85 -1.65) (end -0.85 -1.4) (layer "B.CrtYd") (width 0.05))
    (fp_line (start 0.85 -1.65) (end -0.85 -1.65) (layer "B.CrtYd") (width 0.05))
    (fp_line (start 1.75 0.45) (end 1.75 -0.45) (layer "B.CrtYd") (width 0.05))
    (fp_line (start -0.9 1.6) (end 0.825 1.6) (layer "B.CrtYd") (width 0.05))
    (fp_line (start -1.75 -1.4) (end -1.75 -0.5) (layer "B.CrtYd") (width 0.05))
    (fp_line (start -0.9 1.4) (end -1.75 1.4) (layer "B.CrtYd") (width 0.05))
    (fp_line (start 0.85 -0.45) (end 0.85 -1.65) (layer "B.CrtYd") (width 0.05))
    (fp_line (start -0.85 -1.4) (end -1.75 -1.4) (layer "B.CrtYd") (width 0.05))
    (fp_line (start -1.75 -0.5) (end -0.85 -0.5) (layer "B.CrtYd") (width 0.05))
    (fp_line (start 1.75 -0.45) (end 0.85 -0.45) (layer "B.CrtYd") (width 0.05))
    (fp_line (start 0.825 1.6) (end 0.825 0.45) (layer "B.CrtYd") (width 0.05))
    (fp_line (start -0.437 1.526) (end -0.712 1.325) (layer "B.Fab") (width 0.15))
    (fp_line (start -0.712 1.325) (end -0.712 -1.523) (layer "B.Fab") (width 0.15))
    (fp_line (start -0.437 1.526) (end 0.688 1.526) (layer "B.Fab") (width 0.15))
    (fp_line (start -0.712 -1.519) (end 0.688 -1.519) (layer "B.Fab") (width 0.15))
    (fp_line (start 0.688 -1.519) (end 0.688 1.52) (layer "B.Fab") (width 0.15))
    (pad "1" smd roundrect (at -1.1 0.951 90) (size 1 0.6) (layers "B.Cu" "B.Paste" "B.Mask") (roundrect_rratio 0.15)
      (net 390 "Net-(Q15-Pad1)") (pinfunction "G") (pintype "bidirectional"))
    (pad "2" smd roundrect (at -1.1 -0.949 90) (size 1 0.6) (layers "B.Cu" "B.Paste" "B.Mask") (roundrect_rratio 0.15)
      (net 156 "/PSU/BYPASS_EN") (pinfunction "D") (pintype "bidirectional"))
    (pad "3" smd roundrect (at 1.1 0.0005 90) (size 1 0.6) (layers "B.Cu" "B.Paste" "B.Mask") (roundrect_rratio 0.15)
      (net 74 "VDD") (pinfunction "S") (pintype "bidirectional"))
  )
)
